# S9S_MB_2U (Grand Teton) — schematic netlist excerpt (pin names and nets, part order shuffled) for the footprints in the layout excerpt that follows; sources: Cadence DE-HDL packaged netlist, KiCad conversion of 03242023_DA0F0TMBIJ0_F0T_Motherboard_J_brd_V01_OCP.brd

R287  Q_RES  10K 1% CHIP  pkg 0402LF  page 119 : A = P3V3_AUX ; B = FM_CPU0_PROC_ID1
R1582  Q_RES  2K 1% CHIP  pkg 0402LF  page 183 : A = PU_SMB_PCH_PLD_3V3AUX_SDA ; B = P3V3_AUX
C841  Q_CAP_DIFFBUS  DIFF BUS_0.22UF 6.3V 20% X6S  pkg C0201  page 174 : \1\ = P5E_CPU0_PE1_TX_C_DP<14> ; \2\ = P5E_CPU0_PE1_TX_DP<14>

(kicad_pcb
	(version 20260206)
	(generator "pcbnew")
	(generator_version "10.0")
	(general
		(thickness 1.6)
		(legacy_teardrops no)
	)
	(paper "A4")
	(title_block
		(title "03242023_DA0F0TMBIJ0_F0T_Motherboard_J_brd_V01_OCP.brd")
		(comment 1 "Grand Teton / footprints 1550-1552 of 6105")
	)
	(layers
		(0 "F.Cu" signal "TOP")
		(4 "In1.Cu" signal "GND")
		(6 "In2.Cu" signal "IN1")
		(8 "In3.Cu" signal "GND1")
		(10 "In4.Cu" signal "IN2")
		(12 "In5.Cu" signal "GND2")
		(14 "In6.Cu" signal "IN3")
		(16 "In7.Cu" signal "GND3")
		(18 "In8.Cu" signal "VCC")
		(20 "In9.Cu" signal "VCC1")
		(22 "In10.Cu" signal "GND4")
		(24 "In11.Cu" signal "IN4")
		(26 "In12.Cu" signal "GND5")
		(28 "In13.Cu" signal "IN5")
		(30 "In14.Cu" signal "GND6")
		(32 "In15.Cu" signal "IN6")
		(34 "In16.Cu" signal "GND7")
		(2 "B.Cu" signal "BOTTOM")
		(9 "F.Adhes" user "F.Adhesive")
		(11 "B.Adhes" user "B.Adhesive")
		(13 "F.Paste" user "Package Geometry/Pastemask Top")
		(15 "B.Paste" user "Package Geometry/Pastemask Bottom")
		(5 "F.SilkS" user "Ref Des/Silkscreen Top")
		(7 "B.SilkS" user "Ref Des/Silkscreen Bottom")
		(1 "F.Mask" user "Board Geometry/Soldermask Top")
		(3 "B.Mask" user "Board Geometry/Soldermask Bottom")
		(17 "Dwgs.User" user "User.Drawings")
		(19 "Cmts.User" user "User.Comments")
		(21 "Eco1.User" user "User.Eco1")
		(23 "Eco2.User" user "User.Eco2")
		(25 "Edge.Cuts" user "Board Geometry/Outline")
		(27 "Margin" user)
		(31 "F.CrtYd" user "Package Geometry/Place Bound Top")
		(29 "B.CrtYd" user "Package Geometry/Place Bound Bottom")
		(35 "F.Fab" user "Ref Des/Assembly Top")
		(33 "B.Fab" user "Ref Des/Assembly Bottom")
	)
	(footprint ""
		(layer "F.Cu")
		(at 312.443622 -35.84194 180)
		(property "Reference" "R1582"
			(at 0 0 180)
			(layer "F.SilkS")
			(hide yes)
			(effects
				(font
					(size 1.27 1.27)
				)
			)
		)
		(property "Value" ""
			(at 0 0 180)
			(layer "F.Fab")
			(effects
				(font
					(size 1.27 1.27)
				)
			)
		)
		(duplicate_pad_numbers_are_jumpers no)
		(fp_line
			(start 0.7874 0.4064)
			(end -0.7874 0.4064)
			(stroke
				(width 0.1524)
				(type default)
			)
			(layer "F.SilkS")
		)
		(fp_line
			(start 0.7874 -0.4064)
			(end 0.7874 0.4064)
			(stroke
				(width 0.1524)
				(type default)
			)
			(layer "F.SilkS")
		)
		(fp_line
			(start -0.7874 0.4064)
			(end -0.7874 -0.4064)
			(stroke
				(width 0.1524)
				(type default)
			)
			(layer "F.SilkS")
		)
		(fp_line
			(start -0.7874 -0.4064)
			(end 0.7874 -0.4064)
			(stroke
				(width 0.1524)
				(type default)
			)
			(layer "F.SilkS")
		)
		(fp_line
			(start 0.67945 0.3048)
			(end 0.120396 0.3048)
			(stroke
				(width 0.1)
				(type default)
			)
			(layer "F.Fab")
		)
		(fp_line
			(start 0.67945 -0.3048)
			(end 0.67945 0.3048)
			(stroke
				(width 0.1)
				(type default)
			)
			(layer "F.Fab")
		)
		(fp_line
			(start 0.12065 -0.2794)
			(end 0.12065 -0.3048)
			(stroke
				(width 0.1)
				(type default)
			)
			(layer "F.Fab")
		)
		(fp_line
			(start 0.12065 -0.3048)
			(end 0.67945 -0.3048)
			(stroke
				(width 0.1)
				(type default)
			)
			(layer "F.Fab")
		)
		(fp_line
			(start 0.120396 0.3048)
			(end 0.120396 0.2794)
			(stroke
				(width 0.1)
				(type default)
			)
			(layer "F.Fab")
		)
		(fp_line
			(start 0.120396 0.2794)
			(end -0.12065 0.2794)
			(stroke
				(width 0.1)
				(type default)
			)
			(layer "F.Fab")
		)
		(fp_line
			(start -0.12065 0.3048)
			(end -0.67945 0.3048)
			(stroke
				(width 0.1)
				(type default)
			)
			(layer "F.Fab")
		)
		(fp_line
			(start -0.12065 0.2794)
			(end -0.12065 0.3048)
			(stroke
				(width 0.1)
				(type default)
			)
			(layer "F.Fab")
		)
		(fp_line
			(start -0.12065 -0.2794)
			(end 0.12065 -0.2794)
			(stroke
				(width 0.1)
				(type default)
			)
			(layer "F.Fab")
		)
		(fp_line
			(start -0.12065 -0.305054)
			(end -0.12065 -0.2794)
			(stroke
				(width 0.1)
				(type default)
			)
			(layer "F.Fab")
		)
		(fp_line
			(start -0.67945 0.3048)
			(end -0.67945 -0.305054)
			(stroke
				(width 0.1)
				(type default)
			)
			(layer "F.Fab")
		)
		(fp_line
			(start -0.67945 -0.305054)
			(end -0.12065 -0.305054)
			(stroke
				(width 0.1)
				(type default)
			)
			(layer "F.Fab")
		)
		(pad "1" smd circle
			(at -0.40005 0 180)
			(size 0 0)
			(layers "F.Cu" "F.Mask" "F.Paste")
			(net "PU_SMB_PCH_PLD_3V3AUX_SDA")
		)
		(pad "2" smd circle
			(at 0.40005 0 180)
			(size 0 0)
			(layers "F.Cu" "F.Mask" "F.Paste")
			(net "P3V3_AUX")
		)
	)
	(footprint ""
		(layer "F.Cu")
		(at 393.724384 -17.612614 90)
		(property "Reference" "C841"
			(at 0 0 90)
			(layer "F.SilkS")
			(hide yes)
			(effects
				(font
					(size 1.27 1.27)
				)
			)
		)
		(property "Value" ""
			(at 0 0 90)
			(layer "F.Fab")
			(effects
				(font
					(size 1.27 1.27)
				)
			)
		)
		(duplicate_pad_numbers_are_jumpers no)
		(fp_line
			(start 0.299974 -0.150114)
			(end 0.299974 0.150114)
			(stroke
				(width 0.1)
				(type default)
			)
			(layer "F.Fab")
		)
		(fp_line
			(start -0.299974 -0.150114)
			(end 0.299974 -0.150114)
			(stroke
				(width 0.1)
				(type default)
			)
			(layer "F.Fab")
		)
		(fp_line
			(start 0.299974 0.150114)
			(end -0.299974 0.150114)
			(stroke
				(width 0.1)
				(type default)
			)
			(layer "F.Fab")
		)
		(fp_line
			(start -0.299974 0.150114)
			(end -0.299974 -0.150114)
			(stroke
				(width 0.1)
				(type default)
			)
			(layer "F.Fab")
		)
		(pad "1" smd rect
			(at -0.2667 0 90)
			(size 0.3048 0.381)
			(layers "F.Cu" "F.Mask" "F.Paste")
			(net "P5E_CPU0_PE1_TX_C_DP<14>")
		)
		(pad "2" smd rect
			(at 0.2667 0 90)
			(size 0.3048 0.381)
			(layers "F.Cu" "F.Mask" "F.Paste")
			(net "P5E_CPU0_PE1_TX_DP<14>")
		)
	)
	(footprint ""
		(layer "F.Cu")
		(at 186.74588 -130.266948 -90)
		(property "Reference" "R287"
			(at 0 0 270)
			(layer "F.SilkS")
			(hide yes)
			(effects
				(font
					(size 1.27 1.27)
				)
			)
		)
		(property "Value" ""
			(at 0 0 270)
			(layer "F.Fab")
			(effects
				(font
					(size 1.27 1.27)
				)
			)
		)
		(duplicate_pad_numbers_are_jumpers no)
		(fp_line
			(start -0.7874 0.4064)
			(end -0.7874 -0.4064)
			(stroke
				(width 0.1524)
				(type default)
			)
			(layer "F.SilkS")
		)
		(fp_line
			(start 0.7874 0.4064)
			(end -0.7874 0.4064)
			(stroke
				(width 0.1524)
				(type default)
			)
			(layer "F.SilkS")
		)
		(fp_line
			(start -0.7874 -0.4064)
			(end 0.7874 -0.4064)
			(stroke
				(width 0.1524)
				(type default)
			)
			(layer "F.SilkS")
		)
		(fp_line
			(start 0.7874 -0.4064)
			(end 0.7874 0.4064)
			(stroke
				(width 0.1524)
				(type default)
			)
			(layer "F.SilkS")
		)
		(fp_line
			(start -0.67945 0.3048)
			(end -0.67945 -0.305054)
			(stroke
				(width 0.1)
				(type default)
			)
			(layer "F.Fab")
		)
		(fp_line
			(start -0.12065 0.3048)
			(end -0.67945 0.3048)
			(stroke
				(width 0.1)
				(type default)
			)
			(layer "F.Fab")
		)
		(fp_line
			(start 0.120396 0.3048)
			(end 0.120396 0.2794)
			(stroke
				(width 0.1)
				(type default)
			)
			(layer "F.Fab")
		)
		(fp_line
			(start 0.67945 0.3048)
			(end 0.120396 0.3048)
			(stroke
				(width 0.1)
				(type default)
			)
			(layer "F.Fab")
		)
		(fp_line
			(start -0.12065 0.2794)
			(end -0.12065 0.3048)
			(stroke
				(width 0.1)
				(type default)
			)
			(layer "F.Fab")
		)
		(fp_line
			(start 0.120396 0.2794)
			(end -0.12065 0.2794)
			(stroke
				(width 0.1)
				(type default)
			)
			(layer "F.Fab")
		)
		(fp_line
			(start -0.12065 -0.2794)
			(end 0.12065 -0.2794)
			(stroke
				(width 0.1)
				(type default)
			)
			(layer "F.Fab")
		)
		(fp_line
			(start 0.12065 -0.2794)
			(end 0.12065 -0.3048)
			(stroke
				(width 0.1)
				(type default)
			)
			(layer "F.Fab")
		)
		(fp_line
			(start 0.12065 -0.3048)
			(end 0.67945 -0.3048)
			(stroke
				(width 0.1)
				(type default)
			)
			(layer "F.Fab")
		)
		(fp_line
			(start 0.67945 -0.3048)
			(end 0.67945 0.3048)
			(stroke
				(width 0.1)
				(type default)
			)
			(layer "F.Fab")
		)
		(fp_line
			(start -0.67945 -0.305054)
			(end -0.12065 -0.305054)
			(stroke
				(width 0.1)
				(type default)
			)
			(layer "F.Fab")
		)
		(fp_line
			(start -0.12065 -0.305054)
			(end -0.12065 -0.2794)
			(stroke
				(width 0.1)
				(type default)
			)
			(layer "F.Fab")
		)
		(pad "1" smd circle
			(at -0.40005 0 270)
			(size 0 0)
			(layers "F.Cu" "F.Mask" "F.Paste")
			(net "P3V3_AUX")
		)
		(pad "2" smd circle
			(at 0.40005 0 270)
			(size 0 0)
			(layers "F.Cu" "F.Mask" "F.Paste")
			(net "FM_CPU0_PROC_ID1")
		)
	)
)
